# S9S_MB_2U (Grand Teton) — schematic netlist excerpt (pin names and nets, part order shuffled) for the footprints in the layout excerpt that follows; sources: Cadence DE-HDL packaged netlist, KiCad conversion of 03242023_DA0F0TMBIJ0_F0T_Motherboard_J_brd_V01_OCP.brd

C1118  Q_CAP  0.01UF 50V 10% X7R  pkg C0402  page 217 : A = P3V3_AUX_FPGA_VCCIO3 ; B = GND
C472  Q_CAP  47UF 2.5V 20% X6S  pkg C0603  page 79 : A = PVCCFA_EHV_CPU1 ; B = GND

(kicad_pcb
	(version 20260206)
	(generator "pcbnew")
	(generator_version "10.0")
	(general
		(thickness 1.6)
		(legacy_teardrops no)
	)
	(paper "A4")
	(title_block
		(title "03242023_DA0F0TMBIJ0_F0T_Motherboard_J_brd_V01_OCP.brd")
		(comment 1 "Grand Teton / footprints 4936-4937 of 6105")
	)
	(layers
		(0 "F.Cu" signal "TOP")
		(4 "In1.Cu" signal "GND")
		(6 "In2.Cu" signal "IN1")
		(8 "In3.Cu" signal "GND1")
		(10 "In4.Cu" signal "IN2")
		(12 "In5.Cu" signal "GND2")
		(14 "In6.Cu" signal "IN3")
		(16 "In7.Cu" signal "GND3")
		(18 "In8.Cu" signal "VCC")
		(20 "In9.Cu" signal "VCC1")
		(22 "In10.Cu" signal "GND4")
		(24 "In11.Cu" signal "IN4")
		(26 "In12.Cu" signal "GND5")
		(28 "In13.Cu" signal "IN5")
		(30 "In14.Cu" signal "GND6")
		(32 "In15.Cu" signal "IN6")
		(34 "In16.Cu" signal "GND7")
		(2 "B.Cu" signal "BOTTOM")
		(9 "F.Adhes" user "F.Adhesive")
		(11 "B.Adhes" user "B.Adhesive")
		(13 "F.Paste" user "Package Geometry/Pastemask Top")
		(15 "B.Paste" user "Package Geometry/Pastemask Bottom")
		(5 "F.SilkS" user "Ref Des/Silkscreen Top")
		(7 "B.SilkS" user "Ref Des/Silkscreen Bottom")
		(1 "F.Mask" user "Board Geometry/Soldermask Top")
		(3 "B.Mask" user "Board Geometry/Soldermask Bottom")
		(17 "Dwgs.User" user "User.Drawings")
		(19 "Cmts.User" user "User.Comments")
		(21 "Eco1.User" user "User.Eco1")
		(23 "Eco2.User" user "User.Eco2")
		(25 "Edge.Cuts" user "Board Geometry/Outline")
		(27 "Margin" user)
		(31 "F.CrtYd" user "Package Geometry/Place Bound Top")
		(29 "B.CrtYd" user "Package Geometry/Place Bound Bottom")
		(35 "F.Fab" user "Ref Des/Assembly Top")
		(33 "B.Fab" user "Ref Des/Assembly Bottom")
	)
	(footprint ""
		(layer "B.Cu")
		(at 180.555646 -110.975394 -90)
		(property "Reference" "C1118"
			(at 0 0 90)
			(layer "B.SilkS")
			(hide yes)
			(effects
				(font
					(size 1.27 1.27)
				)
				(justify mirror)
			)
		)
		(property "Value" ""
			(at 0 0 90)
			(layer "B.Fab")
			(effects
				(font
					(size 1.27 1.27)
				)
				(justify mirror)
			)
		)
		(duplicate_pad_numbers_are_jumpers no)
		(fp_line
			(start -0.69215 0.2921)
			(end 0.69215 0.2921)
			(stroke
				(width 0.1524)
				(type default)
			)
			(layer "B.SilkS")
		)
		(fp_line
			(start 0.69215 0.2921)
			(end 0.69215 -0.2921)
			(stroke
				(width 0.1524)
				(type default)
			)
			(layer "B.SilkS")
		)
		(fp_line
			(start -0.69215 -0.2921)
			(end -0.69215 0.2921)
			(stroke
				(width 0.1524)
				(type default)
			)
			(layer "B.SilkS")
		)
		(fp_line
			(start 0.69215 -0.2921)
			(end -0.69215 -0.2921)
			(stroke
				(width 0.1524)
				(type default)
			)
			(layer "B.SilkS")
		)
		(fp_line
			(start -0.51435 0.2794)
			(end 0.51435 0.2794)
			(stroke
				(width 0.1)
				(type default)
			)
			(layer "B.Fab")
		)
		(fp_line
			(start 0.51435 0.2794)
			(end 0.51435 -0.2794)
			(stroke
				(width 0.1)
				(type default)
			)
			(layer "B.Fab")
		)
		(fp_line
			(start -0.51435 -0.2794)
			(end -0.51435 0.2794)
			(stroke
				(width 0.1)
				(type default)
			)
			(layer "B.Fab")
		)
		(fp_line
			(start 0.51435 -0.2794)
			(end -0.51435 -0.2794)
			(stroke
				(width 0.1)
				(type default)
			)
			(layer "B.Fab")
		)
		(pad "1" smd circle
			(at 0.40005 0 90)
			(size 0 0)
			(layers "B.Cu" "B.Mask" "B.Paste")
			(net "P3V3_AUX_FPGA_VCCIO3")
		)
		(pad "2" smd circle
			(at -0.40005 0 90)
			(size 0 0)
			(layers "B.Cu" "B.Mask" "B.Paste")
			(net "GND")
		)
		(zone
			(layer "B.Cu")
			(hatch none 0.5)
			(connect_pads
				(clearance 0)
			)
			(min_thickness 0.25)
			(keepout
				(tracks not_allowed)
				(vias allowed)
				(pads allowed)
				(copperpour not_allowed)
				(footprints allowed)
			)
			(placement
				(enabled no)
				(sheetname "")
			)
			(fill
				(thermal_gap 0.5)
				(thermal_bridge_width 0.5)
				(island_removal_mode 0)
			)
			(polygon
				(pts
					(xy 180.468016 -110.784894) (xy 180.40985 -110.876334) (xy 180.40985 -111.075724) (xy 180.468016 -111.165894)
					(xy 180.643276 -111.165894) (xy 180.701696 -111.075724) (xy 180.701696 -110.876334) (xy 180.64353 -110.784894)
				)
			)
		)
	)
	(footprint ""
		(layer "B.Cu")
		(at 101.404928 -210.418934 180)
		(property "Reference" "C472"
			(at 0 0 0)
			(layer "B.SilkS")
			(hide yes)
			(effects
				(font
					(size 1.27 1.27)
				)
				(justify mirror)
			)
		)
		(property "Value" ""
			(at 0 0 0)
			(layer "B.Fab")
			(effects
				(font
					(size 1.27 1.27)
				)
				(justify mirror)
			)
		)
		(duplicate_pad_numbers_are_jumpers no)
		(fp_line
			(start 1.2954 0.5842)
			(end 1.2954 -0.5842)
			(stroke
				(width 0.1524)
				(type default)
			)
			(layer "B.SilkS")
		)
		(fp_line
			(start 1.2954 -0.5842)
			(end -1.2954 -0.5842)
			(stroke
				(width 0.1524)
				(type default)
			)
			(layer "B.SilkS")
		)
		(fp_line
			(start 0 -0.5842)
			(end 0 0.5842)
			(stroke
				(width 0.1524)
				(type default)
			)
			(layer "B.SilkS")
		)
		(fp_line
			(start -1.2954 0.5842)
			(end 1.2954 0.5842)
			(stroke
				(width 0.1524)
				(type default)
			)
			(layer "B.SilkS")
		)
		(fp_line
			(start -1.2954 -0.5842)
			(end -1.2954 0.5842)
			(stroke
				(width 0.1524)
				(type default)
			)
			(layer "B.SilkS")
		)
		(fp_line
			(start 1.1938 0.4064)
			(end 1.1938 -0.4064)
			(stroke
				(width 0.1)
				(type default)
			)
			(layer "B.Fab")
		)
		(fp_line
			(start 1.1938 -0.4064)
			(end 0.8636 -0.4064)
			(stroke
				(width 0.1)
				(type default)
			)
			(layer "B.Fab")
		)
		(fp_line
			(start 0.8636 0.4572)
			(end 0.8636 0.4064)
			(stroke
				(width 0.1)
				(type default)
			)
			(layer "B.Fab")
		)
		(fp_line
			(start 0.8636 0.4064)
			(end 1.1938 0.4064)
			(stroke
				(width 0.1)
				(type default)
			)
			(layer "B.Fab")
		)
		(fp_line
			(start 0.8636 -0.4064)
			(end 0.8636 -0.4572)
			(stroke
				(width 0.1)
				(type default)
			)
			(layer "B.Fab")
		)
		(fp_line
			(start 0.8636 -0.4572)
			(end -0.8636 -0.4572)
			(stroke
				(width 0.1)
				(type default)
			)
			(layer "B.Fab")
		)
		(fp_line
			(start -0.8636 0.4572)
			(end 0.8636 0.4572)
			(stroke
				(width 0.1)
				(type default)
			)
			(layer "B.Fab")
		)
		(fp_line
			(start -0.8636 0.4064)
			(end -0.8636 0.4572)
			(stroke
				(width 0.1)
				(type default)
			)
			(layer "B.Fab")
		)
		(fp_line
			(start -0.8636 -0.4064)
			(end -1.1938 -0.4064)
			(stroke
				(width 0.1)
				(type default)
			)
			(layer "B.Fab")
		)
		(fp_line
			(start -0.8636 -0.4572)
			(end -0.8636 -0.4064)
			(stroke
				(width 0.1)
				(type default)
			)
			(layer "B.Fab")
		)
		(fp_line
			(start -1.1938 0.4064)
			(end -0.8636 0.4064)
			(stroke
				(width 0.1)
				(type default)
			)
			(layer "B.Fab")
		)
		(fp_line
			(start -1.1938 -0.4064)
			(end -1.1938 0.4064)
			(stroke
				(width 0.1)
				(type default)
			)
			(layer "B.Fab")
		)
		(pad "1" smd rect
			(at 0.7366 0 90)
			(size 0.7112 0.8128)
			(layers "B.Cu" "B.Mask" "B.Paste")
			(net "PVCCFA_EHV_CPU1")
		)
		(pad "2" smd rect
			(at -0.7366 0 90)
			(size 0.7112 0.8128)
			(layers "B.Cu" "B.Mask" "B.Paste")
			(net "GND")
		)
	)
)
